(kicad_pcb
	(version 20260206)
	(generator "pcbnew")
	(generator_version "10.0")
	(general
		(thickness 1.6)
		(legacy_teardrops no)
	)
	(paper "A4")
	(title_block
		(title "01162023_DA0F0TEBIF0_F0T_Expander_BD_F_brd_V02_OCP.brd")
		(comment 1 "Grand Teton / footprints 3751-3758 of 9728")
	)
	(layers
		(0 "F.Cu" signal "TOP")
		(4 "In1.Cu" signal "GND")
		(6 "In2.Cu" signal "VCC")
		(8 "In3.Cu" signal "VCC1")
		(10 "In4.Cu" signal "GND1")
		(12 "In5.Cu" signal "IN1")
		(14 "In6.Cu" signal "GND2")
		(16 "In7.Cu" signal "IN2")
		(18 "In8.Cu" signal "GND3")
		(20 "In9.Cu" signal "IN3")
		(22 "In10.Cu" signal "GND4")
		(24 "In11.Cu" signal "IN4")
		(26 "In12.Cu" signal "GND5")
		(28 "In13.Cu" signal "IN5")
		(30 "In14.Cu" signal "GND6")
		(32 "In15.Cu" signal "IN6")
		(34 "In16.Cu" signal "GND7")
		(2 "B.Cu" signal "BOTTOM")
		(9 "F.Adhes" user "F.Adhesive")
		(11 "B.Adhes" user "B.Adhesive")
		(13 "F.Paste" user "Package Geometry/Pastemask Top")
		(15 "B.Paste" user "Package Geometry/Pastemask Bottom")
		(5 "F.SilkS" user "Ref Des/Silkscreen Top")
		(7 "B.SilkS" user "Ref Des/Silkscreen Bottom")
		(1 "F.Mask" user "Board Geometry/Soldermask Top")
		(3 "B.Mask" user "Board Geometry/Soldermask Bottom")
		(17 "Dwgs.User" user "User.Drawings")
		(19 "Cmts.User" user "User.Comments")
		(21 "Eco1.User" user "User.Eco1")
		(23 "Eco2.User" user "User.Eco2")
		(25 "Edge.Cuts" user "Board Geometry/Outline")
		(27 "Margin" user)
		(31 "F.CrtYd" user "Package Geometry/Place Bound Top")
		(29 "B.CrtYd" user "Package Geometry/Place Bound Bottom")
		(35 "F.Fab" user "Ref Des/Assembly Top")
		(33 "B.Fab" user "Ref Des/Assembly Bottom")
	)
	(footprint ""
		(layer "F.Cu")
		(at 430.961546 -152.511252 180)
		(property "Reference" "C638"
			(at 0 0 180)
			(layer "F.SilkS")
			(hide yes)
			(effects
				(font
					(size 1.27 1.27)
				)
			)
		)
		(property "Value" ""
			(at 0 0 180)
			(layer "F.Fab")
			(effects
				(font
					(size 1.27 1.27)
				)
			)
		)
		(duplicate_pad_numbers_are_jumpers no)
		(fp_line
			(start 0.299974 0.150114)
			(end -0.299974 0.150114)
			(stroke
				(width 0.1)
				(type default)
			)
			(layer "F.Fab")
		)
		(fp_line
			(start 0.299974 -0.150114)
			(end 0.299974 0.150114)
			(stroke
				(width 0.1)
				(type default)
			)
			(layer "F.Fab")
		)
		(fp_line
			(start -0.299974 0.150114)
			(end -0.299974 -0.150114)
			(stroke
				(width 0.1)
				(type default)
			)
			(layer "F.Fab")
		)
		(fp_line
			(start -0.299974 -0.150114)
			(end 0.299974 -0.150114)
			(stroke
				(width 0.1)
				(type default)
			)
			(layer "F.Fab")
		)
		(pad "1" smd rect
			(at -0.2667 0 180)
			(size 0.3048 0.381)
			(layers "F.Cu" "F.Mask" "F.Paste")
			(net "P5E_PEX3_STN0_TX_DP<13>")
		)
		(pad "2" smd rect
			(at 0.2667 0 180)
			(size 0.3048 0.381)
			(layers "F.Cu" "F.Mask" "F.Paste")
			(net "P5E_PEX3_STN0_TX_C_DP<13>")
		)
	)
	(footprint ""
		(layer "F.Cu")
		(at 229.771956 -86.833456 -90)
		(property "Reference" "R1010"
			(at 0 0 270)
			(layer "F.SilkS")
			(hide yes)
			(effects
				(font
					(size 1.27 1.27)
				)
			)
		)
		(property "Value" ""
			(at 0 0 270)
			(layer "F.Fab")
			(effects
				(font
					(size 1.27 1.27)
				)
			)
		)
		(duplicate_pad_numbers_are_jumpers no)
		(fp_line
			(start 0.7874 0.4064)
			(end -0.7874 0.4064)
			(stroke
				(width 0.1524)
				(type default)
			)
			(layer "F.SilkS")
		)
		(fp_line
			(start -0.67945 0.3048)
			(end -0.67945 -0.305054)
			(stroke
				(width 0.1)
				(type default)
			)
			(layer "F.Fab")
		)
		(fp_line
			(start -0.12065 0.3048)
			(end -0.67945 0.3048)
			(stroke
				(width 0.1)
				(type default)
			)
			(layer "F.Fab")
		)
		(fp_line
			(start 0.120396 0.3048)
			(end 0.120396 0.2794)
			(stroke
				(width 0.1)
				(type default)
			)
			(layer "F.Fab")
		)
		(fp_line
			(start 0.67945 0.3048)
			(end 0.120396 0.3048)
			(stroke
				(width 0.1)
				(type default)
			)
			(layer "F.Fab")
		)
		(fp_line
			(start -0.12065 0.2794)
			(end -0.12065 0.3048)
			(stroke
				(width 0.1)
				(type default)
			)
			(layer "F.Fab")
		)
		(fp_line
			(start 0.120396 0.2794)
			(end -0.12065 0.2794)
			(stroke
				(width 0.1)
				(type default)
			)
			(layer "F.Fab")
		)
		(fp_line
			(start -0.12065 -0.2794)
			(end 0.12065 -0.2794)
			(stroke
				(width 0.1)
				(type default)
			)
			(layer "F.Fab")
		)
		(fp_line
			(start 0.12065 -0.2794)
			(end 0.12065 -0.3048)
			(stroke
				(width 0.1)
				(type default)
			)
			(layer "F.Fab")
		)
		(fp_line
			(start 0.12065 -0.3048)
			(end 0.67945 -0.3048)
			(stroke
				(width 0.1)
				(type default)
			)
			(layer "F.Fab")
		)
		(fp_line
			(start 0.67945 -0.3048)
			(end 0.67945 0.3048)
			(stroke
				(width 0.1)
				(type default)
			)
			(layer "F.Fab")
		)
		(fp_line
			(start -0.67945 -0.305054)
			(end -0.12065 -0.305054)
			(stroke
				(width 0.1)
				(type default)
			)
			(layer "F.Fab")
		)
		(fp_line
			(start -0.12065 -0.305054)
			(end -0.12065 -0.2794)
			(stroke
				(width 0.1)
				(type default)
			)
			(layer "F.Fab")
		)
		(pad "1" smd circle
			(at -0.40005 0 270)
			(size 0 0)
			(layers "F.Cu" "F.Mask" "F.Paste")
			(net "USB2_PEX_HUB_R_DN")
		)
		(pad "2" smd circle
			(at 0.40005 0 270)
			(size 0 0)
			(layers "F.Cu" "F.Mask" "F.Paste")
			(net "USB2_PEX_HUB_DN")
		)
	)
	(footprint ""
		(layer "F.Cu")
		(at 231.844596 -278.551386)
		(property "Reference" "R779"
			(at 0 0 0)
			(layer "F.SilkS")
			(hide yes)
			(effects
				(font
					(size 1.27 1.27)
				)
			)
		)
		(property "Value" ""
			(at 0 0 0)
			(layer "F.Fab")
			(effects
				(font
					(size 1.27 1.27)
				)
			)
		)
		(duplicate_pad_numbers_are_jumpers no)
		(fp_line
			(start -0.7874 -0.4064)
			(end 0.7874 -0.4064)
			(stroke
				(width 0.1524)
				(type default)
			)
			(layer "F.SilkS")
		)
		(fp_line
			(start -0.7874 0.4064)
			(end -0.7874 -0.4064)
			(stroke
				(width 0.1524)
				(type default)
			)
			(layer "F.SilkS")
		)
		(fp_line
			(start 0.7874 -0.4064)
			(end 0.7874 0.4064)
			(stroke
				(width 0.1524)
				(type default)
			)
			(layer "F.SilkS")
		)
		(fp_line
			(start 0.7874 0.4064)
			(end -0.7874 0.4064)
			(stroke
				(width 0.1524)
				(type default)
			)
			(layer "F.SilkS")
		)
		(fp_line
			(start -0.67945 -0.305054)
			(end -0.12065 -0.305054)
			(stroke
				(width 0.1)
				(type default)
			)
			(layer "F.Fab")
		)
		(fp_line
			(start -0.67945 0.3048)
			(end -0.67945 -0.305054)
			(stroke
				(width 0.1)
				(type default)
			)
			(layer "F.Fab")
		)
		(fp_line
			(start -0.12065 -0.305054)
			(end -0.12065 -0.2794)
			(stroke
				(width 0.1)
				(type default)
			)
			(layer "F.Fab")
		)
		(fp_line
			(start -0.12065 -0.2794)
			(end 0.12065 -0.2794)
			(stroke
				(width 0.1)
				(type default)
			)
			(layer "F.Fab")
		)
		(fp_line
			(start -0.12065 0.2794)
			(end -0.12065 0.3048)
			(stroke
				(width 0.1)
				(type default)
			)
			(layer "F.Fab")
		)
		(fp_line
			(start -0.12065 0.3048)
			(end -0.67945 0.3048)
			(stroke
				(width 0.1)
				(type default)
			)
			(layer "F.Fab")
		)
		(fp_line
			(start 0.120396 0.2794)
			(end -0.12065 0.2794)
			(stroke
				(width 0.1)
				(type default)
			)
			(layer "F.Fab")
		)
		(fp_line
			(start 0.120396 0.3048)
			(end 0.120396 0.2794)
			(stroke
				(width 0.1)
				(type default)
			)
			(layer "F.Fab")
		)
		(fp_line
			(start 0.12065 -0.3048)
			(end 0.67945 -0.3048)
			(stroke
				(width 0.1)
				(type default)
			)
			(layer "F.Fab")
		)
		(fp_line
			(start 0.12065 -0.2794)
			(end 0.12065 -0.3048)
			(stroke
				(width 0.1)
				(type default)
			)
			(layer "F.Fab")
		)
		(fp_line
			(start 0.67945 -0.3048)
			(end 0.67945 0.3048)
			(stroke
				(width 0.1)
				(type default)
			)
			(layer "F.Fab")
		)
		(fp_line
			(start 0.67945 0.3048)
			(end 0.120396 0.3048)
			(stroke
				(width 0.1)
				(type default)
			)
			(layer "F.Fab")
		)
		(pad "1" smd circle
			(at -0.40005 0)
			(size 0 0)
			(layers "F.Cu" "F.Mask" "F.Paste")
			(net "P3V3_AUX")
		)
		(pad "2" smd circle
			(at 0.40005 0)
			(size 0 0)
			(layers "F.Cu" "F.Mask" "F.Paste")
			(net "PEX_ADC_ALERT_N")
		)
	)
	(footprint ""
		(layer "F.Cu")
		(at 374.8786 -308.611524 45)
		(property "Reference" "R4363"
			(at 0 0 45)
			(layer "F.SilkS")
			(hide yes)
			(effects
				(font
					(size 1.27 1.27)
				)
			)
		)
		(property "Value" ""
			(at 0 0 45)
			(layer "F.Fab")
			(effects
				(font
					(size 1.27 1.27)
				)
			)
		)
		(duplicate_pad_numbers_are_jumpers no)
		(fp_line
			(start -0.787389 -0.406267)
			(end 0.787389 -0.406267)
			(stroke
				(width 0.1524)
				(type default)
			)
			(layer "F.SilkS")
		)
		(fp_line
			(start -0.787389 0.406267)
			(end -0.787389 -0.406267)
			(stroke
				(width 0.1524)
				(type default)
			)
			(layer "F.SilkS")
		)
		(fp_line
			(start 0.787389 -0.406267)
			(end 0.787389 0.406267)
			(stroke
				(width 0.1524)
				(type default)
			)
			(layer "F.SilkS")
		)
		(fp_line
			(start 0.787389 0.406267)
			(end -0.787389 0.406267)
			(stroke
				(width 0.1524)
				(type default)
			)
			(layer "F.SilkS")
		)
		(fp_line
			(start -0.679446 -0.305149)
			(end -0.120695 -0.304969)
			(stroke
				(width 0.1)
				(type default)
			)
			(layer "F.Fab")
		)
		(fp_line
			(start -0.120695 -0.304969)
			(end -0.120695 -0.279466)
			(stroke
				(width 0.1)
				(type default)
			)
			(layer "F.Fab")
		)
		(fp_line
			(start -0.120695 -0.279466)
			(end 0.120695 -0.279466)
			(stroke
				(width 0.1)
				(type default)
			)
			(layer "F.Fab")
		)
		(fp_line
			(start -0.679446 0.30479)
			(end -0.679446 -0.305149)
			(stroke
				(width 0.1)
				(type default)
			)
			(layer "F.Fab")
		)
		(fp_line
			(start 0.120515 -0.30479)
			(end 0.679446 -0.30479)
			(stroke
				(width 0.1)
				(type default)
			)
			(layer "F.Fab")
		)
		(fp_line
			(start 0.120695 -0.279466)
			(end 0.120515 -0.30479)
			(stroke
				(width 0.1)
				(type default)
			)
			(layer "F.Fab")
		)
		(fp_line
			(start -0.120695 0.279466)
			(end -0.120515 0.30479)
			(stroke
				(width 0.1)
				(type default)
			)
			(layer "F.Fab")
		)
		(fp_line
			(start -0.120515 0.30479)
			(end -0.679446 0.30479)
			(stroke
				(width 0.1)
				(type default)
			)
			(layer "F.Fab")
		)
		(fp_line
			(start 0.679446 -0.30479)
			(end 0.679446 0.30479)
			(stroke
				(width 0.1)
				(type default)
			)
			(layer "F.Fab")
		)
		(fp_line
			(start 0.120335 0.279466)
			(end -0.120695 0.279466)
			(stroke
				(width 0.1)
				(type default)
			)
			(layer "F.Fab")
		)
		(fp_line
			(start 0.120515 0.30479)
			(end 0.120335 0.279466)
			(stroke
				(width 0.1)
				(type default)
			)
			(layer "F.Fab")
		)
		(fp_line
			(start 0.679446 0.30479)
			(end 0.120515 0.30479)
			(stroke
				(width 0.1)
				(type default)
			)
			(layer "F.Fab")
		)
		(pad "1" smd circle
			(at -0.40005 0 45)
			(size 0 0)
			(layers "F.Cu" "F.Mask" "F.Paste")
			(net "P1V8_PEX")
		)
		(pad "2" smd circle
			(at 0.40005 0 45)
			(size 0 0)
			(layers "F.Cu" "F.Mask" "F.Paste")
			(net "IRQ_PEX3_CLKREQ_INT_N")
		)
	)
	(footprint ""
		(layer "F.Cu")
		(at 82.150458 -80.581246 90)
		(property "Reference" "U17"
			(at -0.672846 2.382012 90)
			(unlocked yes)
			(layer "F.SilkS")
			(effects
				(font
					(size 0.7874 0.5842)
					(thickness 0.1524)
				)
			)
		)
		(property "Value" ""
			(at 0 0 90)
			(layer "F.Fab")
			(effects
				(font
					(size 1.27 1.27)
				)
			)
		)
		(duplicate_pad_numbers_are_jumpers no)
		(fp_line
			(start 1.905 -1.651)
			(end 1.905 1.651)
			(stroke
				(width 0.1524)
				(type default)
			)
			(layer "F.SilkS")
		)
		(fp_line
			(start -1.905 -1.651)
			(end 1.905 -1.651)
			(stroke
				(width 0.1524)
				(type default)
			)
			(layer "F.SilkS")
		)
		(fp_line
			(start 1.905 1.651)
			(end -1.905 1.651)
			(stroke
				(width 0.1524)
				(type default)
			)
			(layer "F.SilkS")
		)
		(fp_line
			(start -1.905 1.651)
			(end -1.905 -1.651)
			(stroke
				(width 0.1524)
				(type default)
			)
			(layer "F.SilkS")
		)
		(fp_line
			(start 0.6985 -1.524)
			(end 0.6985 -0.219964)
			(stroke
				(width 0.1)
				(type default)
			)
			(layer "F.Fab")
		)
		(fp_line
			(start -0.649986 -1.524)
			(end 0.6985 -1.524)
			(stroke
				(width 0.1)
				(type default)
			)
			(layer "F.Fab")
		)
		(fp_line
			(start -0.649986 -1.169924)
			(end -0.649986 -1.524)
			(stroke
				(width 0.1)
				(type default)
			)
			(layer "F.Fab")
		)
		(fp_line
			(start -1.249934 -1.169924)
			(end -0.649986 -1.169924)
			(stroke
				(width 0.1)
				(type default)
			)
			(layer "F.Fab")
		)
		(fp_line
			(start -0.6985 -0.729996)
			(end -1.249934 -0.729996)
			(stroke
				(width 0.1)
				(type default)
			)
			(layer "F.Fab")
		)
		(fp_line
			(start -1.249934 -0.729996)
			(end -1.249934 -1.169924)
			(stroke
				(width 0.1)
				(type default)
			)
			(layer "F.Fab")
		)
		(fp_line
			(start 1.249934 -0.219964)
			(end 1.249934 0.219964)
			(stroke
				(width 0.1)
				(type default)
			)
			(layer "F.Fab")
		)
		(fp_line
			(start 0.6985 -0.219964)
			(end 1.249934 -0.219964)
			(stroke
				(width 0.1)
				(type default)
			)
			(layer "F.Fab")
		)
		(fp_line
			(start 1.249934 0.219964)
			(end 0.6985 0.219964)
			(stroke
				(width 0.1)
				(type default)
			)
			(layer "F.Fab")
		)
		(fp_line
			(start 0.6985 0.219964)
			(end 0.6985 1.524)
			(stroke
				(width 0.1)
				(type default)
			)
			(layer "F.Fab")
		)
		(fp_line
			(start -0.6985 0.729996)
			(end -0.6985 -0.729996)
			(stroke
				(width 0.1)
				(type default)
			)
			(layer "F.Fab")
		)
		(fp_line
			(start -1.249934 0.729996)
			(end -0.6985 0.729996)
			(stroke
				(width 0.1)
				(type default)
			)
			(layer "F.Fab")
		)
		(fp_line
			(start -0.649986 1.169924)
			(end -1.249934 1.169924)
			(stroke
				(width 0.1)
				(type default)
			)
			(layer "F.Fab")
		)
		(fp_line
			(start -1.249934 1.169924)
			(end -1.249934 0.729996)
			(stroke
				(width 0.1)
				(type default)
			)
			(layer "F.Fab")
		)
		(fp_line
			(start 0.6985 1.524)
			(end -0.649986 1.524)
			(stroke
				(width 0.1)
				(type default)
			)
			(layer "F.Fab")
		)
		(fp_line
			(start -0.649986 1.524)
			(end -0.649986 1.169924)
			(stroke
				(width 0.1)
				(type default)
			)
			(layer "F.Fab")
		)
		(pad "1" smd rect
			(at -1.1176 -1.016)
			(size 1.016 1.27)
			(layers "F.Cu" "F.Mask" "F.Paste")
			(net "HP_NIC1_PWRGD")
		)
		(pad "2" smd rect
			(at -1.1176 1.016)
			(size 1.016 1.27)
			(layers "F.Cu" "F.Mask" "F.Paste")
			(net "P3V3_NIC1")
		)
		(pad "3" smd rect
			(at 1.1176 0)
			(size 1.016 1.27)
			(layers "F.Cu" "F.Mask" "F.Paste")
			(net "GND")
		)
	)
	(footprint ""
		(layer "F.Cu")
		(at 467.58225 -529.13661 180)
		(property "Reference" "J32_OTH"
			(at -3.2385 -1.402334 0)
			(unlocked yes)
			(layer "B.SilkS")
			(effects
				(font
					(size 0.7874 0.5842)
					(thickness 0.1524)
				)
				(justify mirror)
			)
		)
		(property "Value" ""
			(at 0 0 180)
			(layer "F.Fab")
			(effects
				(font
					(size 1.27 1.27)
				)
			)
		)
		(duplicate_pad_numbers_are_jumpers no)
		(pad "1" thru_hole circle
			(at 0 0 180)
			(size 0.4572 0.4572)
			(drill 0.2032)
			(layers "*.Cu" "*.Mask")
			(remove_unused_layers no)
			(net "Net_9104")
			(clearance 0.127)
			(thermal_gap 0.127)
			(padstack
				(mode front_inner_back)
				(layer "Inner"
					(shape circle)
					(size 0.4572 0.4572)
					(clearance 0.127)
				)
				(layer "B.Cu"
					(shape circle)
					(size 0.508 0.508)
					(clearance 0.1016)
				)
			)
		)
	)
	(footprint ""
		(layer "F.Cu")
		(at 235.524294 -49.701958 90)
		(property "Reference" "PC547"
			(at 0 0 90)
			(layer "F.SilkS")
			(hide yes)
			(effects
				(font
					(size 1.27 1.27)
				)
			)
		)
		(property "Value" ""
			(at 0 0 90)
			(layer "F.Fab")
			(effects
				(font
					(size 1.27 1.27)
				)
			)
		)
		(duplicate_pad_numbers_are_jumpers no)
		(fp_line
			(start 1.524 -0.762)
			(end 1.524 0.762)
			(stroke
				(width 0.1524)
				(type default)
			)
			(layer "F.SilkS")
		)
		(fp_line
			(start -1.524 -0.762)
			(end 1.524 -0.762)
			(stroke
				(width 0.1524)
				(type default)
			)
			(layer "F.SilkS")
		)
		(fp_line
			(start 1.524 0.762)
			(end -1.524 0.762)
			(stroke
				(width 0.1524)
				(type default)
			)
			(layer "F.SilkS")
		)
		(fp_line
			(start -1.524 0.762)
			(end -1.524 -0.762)
			(stroke
				(width 0.1524)
				(type default)
			)
			(layer "F.SilkS")
		)
		(fp_line
			(start 1.1049 -0.724916)
			(end -1.1049 -0.724916)
			(stroke
				(width 0.1)
				(type default)
			)
			(layer "F.Fab")
		)
		(fp_line
			(start -1.1049 -0.724916)
			(end -1.1049 0.724916)
			(stroke
				(width 0.1)
				(type default)
			)
			(layer "F.Fab")
		)
		(fp_line
			(start 1.1049 0.724916)
			(end 1.1049 -0.724916)
			(stroke
				(width 0.1)
				(type default)
			)
			(layer "F.Fab")
		)
		(fp_line
			(start -1.1049 0.724916)
			(end 1.1049 0.724916)
			(stroke
				(width 0.1)
				(type default)
			)
			(layer "F.Fab")
		)
		(pad "1" smd rect
			(at -0.889 0 270)
			(size 1.016 1.27)
			(layers "F.Cu" "F.Mask" "F.Paste")
			(net "GND")
		)
		(pad "2" smd rect
			(at 0.889 0 270)
			(size 1.016 1.27)
			(layers "F.Cu" "F.Mask" "F.Paste")
			(net "P3V3_AUX")
		)
	)
	(footprint ""
		(layer "F.Cu")
		(at 365.506 -205.867 180)
		(property "Reference" "R4629"
			(at 0 0 180)
			(layer "F.SilkS")
			(hide yes)
			(effects
				(font
					(size 1.27 1.27)
				)
			)
		)
		(property "Value" ""
			(at 0 0 180)
			(layer "F.Fab")
			(effects
				(font
					(size 1.27 1.27)
				)
			)
		)
		(duplicate_pad_numbers_are_jumpers no)
		(fp_line
			(start 0.7874 0.4064)
			(end -0.7874 0.4064)
			(stroke
				(width 0.1524)
				(type default)
			)
			(layer "F.SilkS")
		)
		(fp_line
			(start 0.7874 -0.4064)
			(end 0.7874 0.4064)
			(stroke
				(width 0.1524)
				(type default)
			)
			(layer "F.SilkS")
		)
		(fp_line
			(start -0.7874 0.4064)
			(end -0.7874 -0.4064)
			(stroke
				(width 0.1524)
				(type default)
			)
			(layer "F.SilkS")
		)
		(fp_line
			(start -0.7874 -0.4064)
			(end 0.7874 -0.4064)
			(stroke
				(width 0.1524)
				(type default)
			)
			(layer "F.SilkS")
		)
		(fp_line
			(start 0.67945 0.3048)
			(end 0.120396 0.3048)
			(stroke
				(width 0.1)
				(type default)
			)
			(layer "F.Fab")
		)
		(fp_line
			(start 0.67945 -0.3048)
			(end 0.67945 0.3048)
			(stroke
				(width 0.1)
				(type default)
			)
			(layer "F.Fab")
		)
		(fp_line
			(start 0.12065 -0.2794)
			(end 0.12065 -0.3048)
			(stroke
				(width 0.1)
				(type default)
			)
			(layer "F.Fab")
		)
		(fp_line
			(start 0.12065 -0.3048)
			(end 0.67945 -0.3048)
			(stroke
				(width 0.1)
				(type default)
			)
			(layer "F.Fab")
		)
		(fp_line
			(start 0.120396 0.3048)
			(end 0.120396 0.2794)
			(stroke
				(width 0.1)
				(type default)
			)
			(layer "F.Fab")
		)
		(fp_line
			(start 0.120396 0.2794)
			(end -0.12065 0.2794)
			(stroke
				(width 0.1)
				(type default)
			)
			(layer "F.Fab")
		)
		(fp_line
			(start -0.12065 0.3048)
			(end -0.67945 0.3048)
			(stroke
				(width 0.1)
				(type default)
			)
			(layer "F.Fab")
		)
		(fp_line
			(start -0.12065 0.2794)
			(end -0.12065 0.3048)
			(stroke
				(width 0.1)
				(type default)
			)
			(layer "F.Fab")
		)
		(fp_line
			(start -0.12065 -0.2794)
			(end 0.12065 -0.2794)
			(stroke
				(width 0.1)
				(type default)
			)
			(layer "F.Fab")
		)
		(fp_line
			(start -0.12065 -0.305054)
			(end -0.12065 -0.2794)
			(stroke
				(width 0.1)
				(type default)
			)
			(layer "F.Fab")
		)
		(fp_line
			(start -0.67945 0.3048)
			(end -0.67945 -0.305054)
			(stroke
				(width 0.1)
				(type default)
			)
			(layer "F.Fab")
		)
		(fp_line
			(start -0.67945 -0.305054)
			(end -0.12065 -0.305054)
			(stroke
				(width 0.1)
				(type default)
			)
			(layer "F.Fab")
		)
		(pad "1" smd circle
			(at -0.40005 0 180)
			(size 0 0)
			(layers "F.Cu" "F.Mask" "F.Paste")
			(net "RST_PEX_SSD1_PERST_N")
		)
		(pad "2" smd circle
			(at 0.40005 0 180)
			(size 0 0)
			(layers "F.Cu" "F.Mask" "F.Paste")
			(net "RST_PEX_SSD1_PERST_R_N")
		)
	)
)
